# BASEBOARD_FAB2 (Tioga Pass) — schematic netlist excerpt (pin names and nets, part order shuffled) for the footprints in the layout excerpt that follows; sources: Cadence DE-HDL packaged netlist, KiCad conversion of Wiwynn_Tioga_Pass_MB.brd

R8W2  RES  1.00K 1% CHIP  pkg 0402  page 235 : A = PU_PVNN_PCH_VCLK ; B = VR_PVNN_P1V05_PCH_VD12
R4D9  RES  27.4 1% CHIP  pkg 0402  page 103 : A = CLK_100M_CPU1_BCLK2_R_DP ; B = CLK_100M_CPU1_BCLK2_DP
R1G7  RES  150.0 1% CHIP  pkg 0402  page 223 : A = SVID_CLK1_CPU1_R ; B = SVID_CLK_PVDDQ_GHJ

(kicad_pcb
	(version 20260206)
	(generator "pcbnew")
	(generator_version "10.0")
	(general
		(thickness 1.6)
		(legacy_teardrops no)
	)
	(paper "A4")
	(title_block
		(title "Wiwynn_Tioga_Pass_MB.brd")
		(comment 1 "Tioga Pass / footprints 602-604 of 4770")
	)
	(layers
		(0 "F.Cu" signal "TOP")
		(4 "In1.Cu" signal "L2GND")
		(6 "In2.Cu" signal "L3")
		(8 "In3.Cu" signal "L4GND")
		(10 "In4.Cu" signal "L5")
		(12 "In5.Cu" signal "L6GND")
		(14 "In6.Cu" signal "L7VCC")
		(16 "In7.Cu" signal "L8VCC")
		(18 "In8.Cu" signal "L9GND")
		(20 "In9.Cu" signal "L10")
		(22 "In10.Cu" signal "L11GND")
		(24 "In11.Cu" signal "L12")
		(26 "In12.Cu" signal "L13GND")
		(2 "B.Cu" signal "BOTTOM")
		(9 "F.Adhes" user "F.Adhesive")
		(11 "B.Adhes" user "B.Adhesive")
		(13 "F.Paste" user "Package Geometry/Pastemask Top")
		(15 "B.Paste" user "Package Geometry/Pastemask Bottom")
		(5 "F.SilkS" user "Ref Des/Silkscreen Top")
		(7 "B.SilkS" user "Ref Des/Silkscreen Bottom")
		(1 "F.Mask" user "Board Geometry/Soldermask Top")
		(3 "B.Mask" user "Board Geometry/Soldermask Bottom")
		(17 "Dwgs.User" user "User.Drawings")
		(19 "Cmts.User" user "User.Comments")
		(21 "Eco1.User" user "User.Eco1")
		(23 "Eco2.User" user "User.Eco2")
		(25 "Edge.Cuts" user "Board Geometry/Outline")
		(27 "Margin" user)
		(31 "F.CrtYd" user "Package Geometry/Place Bound Top")
		(29 "B.CrtYd" user "Package Geometry/Place Bound Bottom")
		(35 "F.Fab" user "Ref Des/Assembly Top")
		(33 "B.Fab" user "Ref Des/Assembly Bottom")
	)
	(footprint ""
		(layer "F.Cu")
		(at 400.558 -154.19324 180)
		(property "Reference" "R8W2"
			(at -0.8382 -0.67818 180)
			(unlocked yes)
			(layer "F.SilkS")
			(effects
				(font
					(size 0.4064 0.254)
					(thickness 0.1524)
				)
				(justify left)
			)
		)
		(property "Value" ""
			(at 0 0 180)
			(layer "F.Fab")
			(effects
				(font
					(size 1.27 1.27)
				)
			)
		)
		(duplicate_pad_numbers_are_jumpers no)
		(fp_poly
			(pts
				(xy -0.2794 -0.1016) (xy 0.2794 -0.1016) (xy 0.2794 0.9906) (xy -0.2794 0.9906)
			)
			(stroke
				(width 0)
				(type default)
			)
			(fill no)
			(layer "F.CrtYd")
		)
		(fp_line
			(start 0.2794 0.9906)
			(end 0.2794 -0.1016)
			(stroke
				(width 0.1)
				(type default)
			)
			(layer "F.Fab")
		)
		(fp_line
			(start 0.2794 -0.1016)
			(end -0.2794 -0.1016)
			(stroke
				(width 0.1)
				(type default)
			)
			(layer "F.Fab")
		)
		(fp_line
			(start -0.2794 0.9906)
			(end 0.2794 0.9906)
			(stroke
				(width 0.1)
				(type default)
			)
			(layer "F.Fab")
		)
		(fp_line
			(start -0.2794 -0.1016)
			(end -0.2794 0.9906)
			(stroke
				(width 0.1)
				(type default)
			)
			(layer "F.Fab")
		)
		(pad "1" smd rect
			(at 0 0 180)
			(size 0.508 0.508)
			(layers "F.Cu" "F.Mask" "F.Paste")
			(net "PU_PVNN_PCH_VCLK")
		)
		(pad "2" smd rect
			(at 0 0.889 180)
			(size 0.508 0.508)
			(layers "F.Cu" "F.Mask" "F.Paste")
			(net "VR_PVNN_P1V05_PCH_VD12")
		)
		(zone
			(layer "F.Cu")
			(hatch none 0.5)
			(connect_pads
				(clearance 0)
			)
			(min_thickness 0.25)
			(keepout
				(tracks not_allowed)
				(vias allowed)
				(pads allowed)
				(copperpour not_allowed)
				(footprints allowed)
			)
			(placement
				(enabled no)
				(sheetname "")
			)
			(fill
				(thermal_gap 0.5)
				(thermal_bridge_width 0.5)
				(island_removal_mode 0)
			)
			(polygon
				(pts
					(xy 400.812 -154.82824) (xy 400.304 -154.82824) (xy 400.304 -154.44724) (xy 400.812 -154.44724)
				)
			)
		)
		(zone
			(layer "F.Cu")
			(hatch none 0.5)
			(connect_pads
				(clearance 0)
			)
			(min_thickness 0.25)
			(keepout
				(tracks allowed)
				(vias not_allowed)
				(pads allowed)
				(copperpour not_allowed)
				(footprints allowed)
			)
			(placement
				(enabled no)
				(sheetname "")
			)
			(fill
				(thermal_gap 0.5)
				(thermal_bridge_width 0.5)
				(island_removal_mode 0)
			)
			(polygon
				(pts
					(xy 400.812 -154.44724) (xy 400.304 -154.44724) (xy 400.304 -154.82824) (xy 400.812 -154.82824)
				)
			)
		)
	)
	(footprint ""
		(layer "F.Cu")
		(at 11.130026 -4.419854)
		(property "Reference" "R1G7"
			(at 0 0 0)
			(layer "F.SilkS")
			(hide yes)
			(effects
				(font
					(size 1.27 1.27)
				)
			)
		)
		(property "Value" ""
			(at 0 0 0)
			(layer "F.Fab")
			(effects
				(font
					(size 1.27 1.27)
				)
			)
		)
		(duplicate_pad_numbers_are_jumpers no)
		(fp_rect
			(start -0.2794 -0.1016)
			(end 0.2794 0.9906)
			(stroke
				(width 0)
				(type default)
			)
			(fill no)
			(layer "F.CrtYd")
		)
		(fp_line
			(start -0.2794 -0.1016)
			(end -0.2794 0.9906)
			(stroke
				(width 0.1)
				(type default)
			)
			(layer "F.Fab")
		)
		(fp_line
			(start -0.2794 0.9906)
			(end 0.2794 0.9906)
			(stroke
				(width 0.1)
				(type default)
			)
			(layer "F.Fab")
		)
		(fp_line
			(start 0.2794 -0.1016)
			(end -0.2794 -0.1016)
			(stroke
				(width 0.1)
				(type default)
			)
			(layer "F.Fab")
		)
		(fp_line
			(start 0.2794 0.9906)
			(end 0.2794 -0.1016)
			(stroke
				(width 0.1)
				(type default)
			)
			(layer "F.Fab")
		)
		(pad "1" smd rect
			(at 0 0)
			(size 0.508 0.508)
			(layers "F.Cu" "F.Mask" "F.Paste")
			(net "SVID_CLK1_CPU1_R")
		)
		(pad "2" smd rect
			(at 0 0.889)
			(size 0.508 0.508)
			(layers "F.Cu" "F.Mask" "F.Paste")
			(net "SVID_CLK_PVDDQ_GHJ")
		)
		(zone
			(layer "F.Cu")
			(hatch none 0.5)
			(connect_pads
				(clearance 0)
			)
			(min_thickness 0.25)
			(keepout
				(tracks allowed)
				(vias not_allowed)
				(pads allowed)
				(copperpour not_allowed)
				(footprints allowed)
			)
			(placement
				(enabled no)
				(sheetname "")
			)
			(fill
				(thermal_gap 0.5)
				(thermal_bridge_width 0.5)
				(island_removal_mode 0)
			)
			(polygon
				(pts
					(xy 10.876026 -4.165854) (xy 10.876026 -3.784854) (xy 11.384026 -3.784854) (xy 11.384026 -4.165854)
				)
			)
		)
		(zone
			(layer "F.Cu")
			(hatch none 0.5)
			(connect_pads
				(clearance 0)
			)
			(min_thickness 0.25)
			(keepout
				(tracks not_allowed)
				(vias allowed)
				(pads allowed)
				(copperpour not_allowed)
				(footprints allowed)
			)
			(placement
				(enabled no)
				(sheetname "")
			)
			(fill
				(thermal_gap 0.5)
				(thermal_bridge_width 0.5)
				(island_removal_mode 0)
			)
			(polygon
				(pts
					(xy 10.876026 -4.165854) (xy 10.876026 -3.784854) (xy 11.384026 -3.784854) (xy 11.384026 -4.165854)
				)
			)
		)
	)
	(footprint ""
		(layer "F.Cu")
		(at 163.576 -85.598 -90)
		(property "Reference" "R4D9"
			(at 0 0 270)
			(layer "F.SilkS")
			(hide yes)
			(effects
				(font
					(size 1.27 1.27)
				)
			)
		)
		(property "Value" ""
			(at 0 0 270)
			(layer "F.Fab")
			(effects
				(font
					(size 1.27 1.27)
				)
			)
		)
		(duplicate_pad_numbers_are_jumpers no)
		(fp_poly
			(pts
				(xy -0.2794 -0.1016) (xy 0.2794 -0.1016) (xy 0.2794 0.9906) (xy -0.2794 0.9906)
			)
			(stroke
				(width 0)
				(type default)
			)
			(fill no)
			(layer "F.CrtYd")
		)
		(fp_line
			(start -0.2794 0.9906)
			(end 0.2794 0.9906)
			(stroke
				(width 0.1)
				(type default)
			)
			(layer "F.Fab")
		)
		(fp_line
			(start 0.2794 0.9906)
			(end 0.2794 -0.1016)
			(stroke
				(width 0.1)
				(type default)
			)
			(layer "F.Fab")
		)
		(fp_line
			(start -0.2794 -0.1016)
			(end -0.2794 0.9906)
			(stroke
				(width 0.1)
				(type default)
			)
			(layer "F.Fab")
		)
		(fp_line
			(start 0.2794 -0.1016)
			(end -0.2794 -0.1016)
			(stroke
				(width 0.1)
				(type default)
			)
			(layer "F.Fab")
		)
		(pad "1" smd rect
			(at 0 0 270)
			(size 0.508 0.508)
			(layers "F.Cu" "F.Mask" "F.Paste")
			(net "CLK_100M_CPU1_BCLK2_R_DP")
		)
		(pad "2" smd rect
			(at 0 0.889 270)
			(size 0.508 0.508)
			(layers "F.Cu" "F.Mask" "F.Paste")
			(net "CLK_100M_CPU1_BCLK2_DP")
		)
		(zone
			(layer "F.Cu")
			(hatch none 0.5)
			(connect_pads
				(clearance 0)
			)
			(min_thickness 0.25)
			(keepout
				(tracks not_allowed)
				(vias allowed)
				(pads allowed)
				(copperpour not_allowed)
				(footprints allowed)
			)
			(placement
				(enabled no)
				(sheetname "")
			)
			(fill
				(thermal_gap 0.5)
				(thermal_bridge_width 0.5)
				(island_removal_mode 0)
			)
			(polygon
				(pts
					(xy 162.941 -85.852) (xy 162.941 -85.344) (xy 163.322 -85.344) (xy 163.322 -85.852)
				)
			)
		)
		(zone
			(layer "F.Cu")
			(hatch none 0.5)
			(connect_pads
				(clearance 0)
			)
			(min_thickness 0.25)
			(keepout
				(tracks allowed)
				(vias not_allowed)
				(pads allowed)
				(copperpour not_allowed)
				(footprints allowed)
			)
			(placement
				(enabled no)
				(sheetname "")
			)
			(fill
				(thermal_gap 0.5)
				(thermal_bridge_width 0.5)
				(island_removal_mode 0)
			)
			(polygon
				(pts
					(xy 163.322 -85.852) (xy 163.322 -85.344) (xy 162.941 -85.344) (xy 162.941 -85.852)
				)
			)
		)
	)
)
